(kicad_pcb
	(version 20260206)
	(generator "pcbnew")
	(generator_version "10.0")
	(general
		(thickness 1.6)
		(legacy_teardrops no)
	)
	(paper "A4")
	(title_block
		(title "fcb — 12433-1M.1206WZS1330.brd")
		(comment 1 "Open Vault / Knox (Wiwynn) / footprints 1-6 of 495")
	)
	(layers
		(0 "F.Cu" signal "TOP")
		(4 "In1.Cu" signal "L2GND")
		(6 "In2.Cu" signal "L3VCC")
		(2 "B.Cu" signal "BOTTOM")
		(9 "F.Adhes" user "F.Adhesive")
		(11 "B.Adhes" user "B.Adhesive")
		(13 "F.Paste" user "Package Geometry/Pastemask Top")
		(15 "B.Paste" user "Package Geometry/Pastemask Bottom")
		(5 "F.SilkS" user "Ref Des/Silkscreen Top")
		(7 "B.SilkS" user "Ref Des/Silkscreen Bottom")
		(1 "F.Mask" user "Board Geometry/Soldermask Top")
		(3 "B.Mask" user "Board Geometry/Soldermask Bottom")
		(17 "Dwgs.User" user "User.Drawings")
		(19 "Cmts.User" user "User.Comments")
		(21 "Eco1.User" user "User.Eco1")
		(23 "Eco2.User" user "User.Eco2")
		(25 "Edge.Cuts" user "Board Geometry/Outline")
		(27 "Margin" user)
		(31 "F.CrtYd" user "Package Geometry/Place Bound Top")
		(29 "B.CrtYd" user "Package Geometry/Place Bound Bottom")
		(35 "F.Fab" user "Ref Des/Assembly Top")
		(33 "B.Fab" user "Ref Des/Assembly Bottom")
	)
	(footprint ""
		(layer "F.Cu")
		(at 28.2956 -361.0864 -90)
		(property "Reference" "PR16"
			(at 0 0 270)
			(layer "F.SilkS")
			(hide yes)
			(effects
				(font
					(size 1.27 1.27)
				)
			)
		)
		(property "Value" "1KR2F-3-GP"
			(at 0.064008 -3.993896 270)
			(unlocked yes)
			(layer "F.Fab")
			(hide yes)
			(effects
				(font
					(size 1.016 1.016)
					(thickness 0.1524)
				)
			)
		)
		(property "Device Type" "R402H16"
			(at 0.064008 -5.517896 270)
			(unlocked yes)
			(layer "F.Fab")
			(hide yes)
			(effects
				(font
					(size 1.016 1.016)
					(thickness 0.1524)
				)
			)
		)
		(duplicate_pad_numbers_are_jumpers no)
		(fp_line
			(start -0.508 -0.9398)
			(end -0.508 0.9398)
			(stroke
				(width 0.1524)
				(type default)
			)
			(layer "F.SilkS")
		)
		(fp_line
			(start 0.508 -0.9398)
			(end -0.508 -0.9398)
			(stroke
				(width 0.1524)
				(type default)
			)
			(layer "F.SilkS")
		)
		(fp_rect
			(start -0.508 0.9398)
			(end 0.508 -0.9398)
			(stroke
				(width 0)
				(type default)
			)
			(fill no)
			(layer "F.CrtYd")
		)
		(fp_rect
			(start -0.508 0.9398)
			(end 0.508 -0.9398)
			(stroke
				(width 0)
				(type default)
			)
			(fill no)
			(layer "F.Fab")
		)
		(pad "1" smd custom
			(at 0 -0.4445 270)
			(size 0.1397 0.1397)
			(layers "F.Cu" "F.Mask" "F.Paste")
			(net "ADM1276_EN")
			(options
				(clearance outline)
				(anchor circle)
			)
			(primitives
				(gr_poly
					(pts
						(arc
							(start -0.1778 -0.2794)
							(mid -0.249642 -0.249642)
							(end -0.2794 -0.1778)
						)
						(arc
							(start -0.2794 0.1778)
							(mid -0.249642 0.249642)
							(end -0.1778 0.2794)
						)
						(arc
							(start 0.1778 0.2794)
							(mid 0.249642 0.249642)
							(end 0.2794 0.1778)
						)
						(arc
							(start 0.2794 -0.1778)
							(mid 0.249642 -0.249642)
							(end 0.1778 -0.2794)
						)
					)
					(width 0)
					(fill yes)
				)
			)
		)
		(pad "2" smd custom
			(at 0 0.4445 270)
			(size 0.1397 0.1397)
			(layers "F.Cu" "F.Mask" "F.Paste")
			(net "GND")
			(options
				(clearance outline)
				(anchor circle)
			)
			(primitives
				(gr_poly
					(pts
						(arc
							(start -0.1778 -0.2794)
							(mid -0.249642 -0.249642)
							(end -0.2794 -0.1778)
						)
						(arc
							(start -0.2794 0.1778)
							(mid -0.249642 0.249642)
							(end -0.1778 0.2794)
						)
						(arc
							(start 0.1778 0.2794)
							(mid 0.249642 0.249642)
							(end 0.2794 0.1778)
						)
						(arc
							(start 0.2794 -0.1778)
							(mid 0.249642 -0.249642)
							(end 0.1778 -0.2794)
						)
					)
					(width 0)
					(fill yes)
				)
			)
		)
	)
	(footprint ""
		(layer "F.Cu")
		(at 31.75 -357.048816)
		(property "Reference" "Q49"
			(at 0 0 0)
			(layer "F.SilkS")
			(hide yes)
			(effects
				(font
					(size 1.27 1.27)
				)
			)
		)
		(property "Value" "2N7002-11-GP"
			(at 0.127 -8.9662 0)
			(unlocked yes)
			(layer "F.Fab")
			(hide yes)
			(effects
				(font
					(size 1.016 1.016)
					(thickness 0.1524)
				)
			)
		)
		(property "Device Type" "SOT23DGS2D4H44"
			(at 0.127 -10.4902 0)
			(unlocked yes)
			(layer "F.Fab")
			(hide yes)
			(effects
				(font
					(size 1.016 1.016)
					(thickness 0.1524)
				)
			)
		)
		(duplicate_pad_numbers_are_jumpers no)
		(fp_line
			(start -1.651 -1.778)
			(end -1.651 1.778)
			(stroke
				(width 0.1524)
				(type default)
			)
			(layer "F.SilkS")
		)
		(fp_line
			(start -1.651 1.778)
			(end 1.651 1.778)
			(stroke
				(width 0.1524)
				(type default)
			)
			(layer "F.SilkS")
		)
		(fp_line
			(start 1.651 -1.778)
			(end -1.651 -1.778)
			(stroke
				(width 0.1524)
				(type default)
			)
			(layer "F.SilkS")
		)
		(fp_line
			(start 1.651 1.778)
			(end 1.651 -1.778)
			(stroke
				(width 0.1524)
				(type default)
			)
			(layer "F.SilkS")
		)
		(fp_poly
			(pts
				(xy -1.778 1.8796) (xy -1.778 -1.8796) (xy 1.778 -1.8796) (xy 1.778 1.8796)
			)
			(stroke
				(width 0)
				(type default)
			)
			(fill no)
			(layer "F.CrtYd")
		)
		(fp_poly
			(pts
				(xy -1.778 1.8796) (xy -1.778 -1.8796) (xy 1.778 -1.8796) (xy 1.778 1.8796)
			)
			(stroke
				(width 0)
				(type default)
			)
			(fill no)
			(layer "F.Fab")
		)
		(pad "D" smd custom
			(at 0 -0.9525)
			(size 0.1905 0.1905)
			(layers "F.Cu" "F.Mask" "F.Paste")
			(net "ADM1276_EN")
			(options
				(clearance outline)
				(anchor circle)
			)
			(primitives
				(gr_poly
					(pts
						(arc
							(start -0.1778 0.5715)
							(mid -0.321484 0.511984)
							(end -0.381 0.3683)
						)
						(arc
							(start -0.381 -0.3683)
							(mid -0.321484 -0.511984)
							(end -0.1778 -0.5715)
						)
						(arc
							(start 0.1778 -0.5715)
							(mid 0.321484 -0.511984)
							(end 0.381 -0.3683)
						)
						(arc
							(start 0.381 0.3683)
							(mid 0.321484 0.511984)
							(end 0.1778 0.5715)
						)
					)
					(width 0)
					(fill yes)
				)
			)
		)
		(pad "G" smd custom
			(at -0.98425 0.9525)
			(size 0.1905 0.1905)
			(layers "F.Cu" "F.Mask" "F.Paste")
			(net "OTP_RETRY_G")
			(options
				(clearance outline)
				(anchor circle)
			)
			(primitives
				(gr_poly
					(pts
						(arc
							(start -0.1778 0.5715)
							(mid -0.321484 0.511984)
							(end -0.381 0.3683)
						)
						(arc
							(start -0.381 -0.3683)
							(mid -0.321484 -0.511984)
							(end -0.1778 -0.5715)
						)
						(arc
							(start 0.1778 -0.5715)
							(mid 0.321484 -0.511984)
							(end 0.381 -0.3683)
						)
						(arc
							(start 0.381 0.3683)
							(mid 0.321484 0.511984)
							(end 0.1778 0.5715)
						)
					)
					(width 0)
					(fill yes)
				)
			)
		)
		(pad "S" smd custom
			(at 0.98425 0.9525)
			(size 0.1905 0.1905)
			(layers "F.Cu" "F.Mask" "F.Paste")
			(net "GND")
			(options
				(clearance outline)
				(anchor circle)
			)
			(primitives
				(gr_poly
					(pts
						(arc
							(start -0.1778 0.5715)
							(mid -0.321484 0.511984)
							(end -0.381 0.3683)
						)
						(arc
							(start -0.381 -0.3683)
							(mid -0.321484 -0.511984)
							(end -0.1778 -0.5715)
						)
						(arc
							(start 0.1778 -0.5715)
							(mid 0.321484 -0.511984)
							(end 0.381 -0.3683)
						)
						(arc
							(start 0.381 0.3683)
							(mid 0.321484 0.511984)
							(end 0.1778 0.5715)
						)
					)
					(width 0)
					(fill yes)
				)
			)
		)
	)
	(footprint ""
		(layer "F.Cu")
		(at 17.6276 -290.703 -90)
		(property "Reference" "C43"
			(at 0 0 270)
			(layer "F.SilkS")
			(hide yes)
			(effects
				(font
					(size 1.27 1.27)
				)
			)
		)
		(property "Value" "SCD1U16V2KX-3GP"
			(at 1.1811 -2.7051 270)
			(unlocked yes)
			(layer "F.Fab")
			(hide yes)
			(effects
				(font
					(size 1.016 1.016)
					(thickness 0.1524)
				)
			)
		)
		(property "Device Type" "C402H22"
			(at 1.1811 -4.2291 270)
			(unlocked yes)
			(layer "F.Fab")
			(hide yes)
			(effects
				(font
					(size 1.016 1.016)
					(thickness 0.1524)
				)
			)
		)
		(duplicate_pad_numbers_are_jumpers no)
		(fp_rect
			(start -0.4318 0.9525)
			(end 0.4318 -0.9525)
			(stroke
				(width 0)
				(type default)
			)
			(fill no)
			(layer "F.CrtYd")
		)
		(fp_rect
			(start -0.4318 0.9525)
			(end 0.4318 -0.9525)
			(stroke
				(width 0)
				(type default)
			)
			(fill no)
			(layer "F.Fab")
		)
		(pad "1" smd custom
			(at 0 -0.4445 270)
			(size 0.1524 0.1524)
			(layers "F.Cu" "F.Mask" "F.Paste")
			(net "FAN_TACH3")
			(options
				(clearance outline)
				(anchor circle)
			)
			(primitives
				(gr_poly
					(pts
						(arc
							(start 0.3048 -0.2032)
							(mid 0.275042 -0.275042)
							(end 0.2032 -0.3048)
						)
						(arc
							(start -0.2032 -0.3048)
							(mid -0.275042 -0.275042)
							(end -0.3048 -0.2032)
						)
						(arc
							(start -0.3048 0.2032)
							(mid -0.275042 0.275042)
							(end -0.2032 0.3048)
						)
						(arc
							(start 0.2032 0.3048)
							(mid 0.275042 0.275042)
							(end 0.3048 0.2032)
						)
					)
					(width 0)
					(fill yes)
				)
			)
		)
		(pad "2" smd custom
			(at 0 0.4445 270)
			(size 0.1524 0.1524)
			(layers "F.Cu" "F.Mask" "F.Paste")
			(net "GND")
			(options
				(clearance outline)
				(anchor circle)
			)
			(primitives
				(gr_poly
					(pts
						(arc
							(start 0.3048 -0.2032)
							(mid 0.275042 -0.275042)
							(end 0.2032 -0.3048)
						)
						(arc
							(start -0.2032 -0.3048)
							(mid -0.275042 -0.275042)
							(end -0.3048 -0.2032)
						)
						(arc
							(start -0.3048 0.2032)
							(mid -0.275042 0.275042)
							(end -0.2032 0.3048)
						)
						(arc
							(start 0.2032 0.3048)
							(mid 0.275042 0.275042)
							(end 0.3048 0.2032)
						)
					)
					(width 0)
					(fill yes)
				)
			)
		)
	)
	(footprint ""
		(layer "F.Cu")
		(at 6.5786 -437.7436)
		(property "Reference" "R32"
			(at 0 0 0)
			(layer "F.SilkS")
			(hide yes)
			(effects
				(font
					(size 1.27 1.27)
				)
			)
		)
		(property "Value" "0R2J-2-GP"
			(at 0.064008 -3.993896 0)
			(unlocked yes)
			(layer "F.Fab")
			(hide yes)
			(effects
				(font
					(size 1.016 1.016)
					(thickness 0.1524)
				)
			)
		)
		(property "Device Type" "R402H16"
			(at 0.064008 -5.517896 0)
			(unlocked yes)
			(layer "F.Fab")
			(hide yes)
			(effects
				(font
					(size 1.016 1.016)
					(thickness 0.1524)
				)
			)
		)
		(duplicate_pad_numbers_are_jumpers no)
		(fp_line
			(start -0.508 -0.9398)
			(end -0.508 0.9398)
			(stroke
				(width 0.1524)
				(type default)
			)
			(layer "F.SilkS")
		)
		(fp_line
			(start 0.508 -0.9398)
			(end -0.508 -0.9398)
			(stroke
				(width 0.1524)
				(type default)
			)
			(layer "F.SilkS")
		)
		(fp_rect
			(start -0.508 0.9398)
			(end 0.508 -0.9398)
			(stroke
				(width 0)
				(type default)
			)
			(fill no)
			(layer "F.CrtYd")
		)
		(fp_rect
			(start -0.508 0.9398)
			(end 0.508 -0.9398)
			(stroke
				(width 0)
				(type default)
			)
			(fill no)
			(layer "F.Fab")
		)
		(pad "1" smd custom
			(at 0 -0.4445)
			(size 0.1397 0.1397)
			(layers "F.Cu" "F.Mask" "F.Paste")
			(net "LED_DR_LED0_K")
			(options
				(clearance outline)
				(anchor circle)
			)
			(primitives
				(gr_poly
					(pts
						(arc
							(start -0.1778 -0.2794)
							(mid -0.249642 -0.249642)
							(end -0.2794 -0.1778)
						)
						(arc
							(start -0.2794 0.1778)
							(mid -0.249642 0.249642)
							(end -0.1778 0.2794)
						)
						(arc
							(start 0.1778 0.2794)
							(mid 0.249642 0.249642)
							(end 0.2794 0.1778)
						)
						(arc
							(start 0.2794 -0.1778)
							(mid 0.249642 -0.249642)
							(end 0.1778 -0.2794)
						)
					)
					(width 0)
					(fill yes)
				)
			)
		)
		(pad "2" smd custom
			(at 0 0.4445)
			(size 0.1397 0.1397)
			(layers "F.Cu" "F.Mask" "F.Paste")
			(net "GND")
			(options
				(clearance outline)
				(anchor circle)
			)
			(primitives
				(gr_poly
					(pts
						(arc
							(start -0.1778 -0.2794)
							(mid -0.249642 -0.249642)
							(end -0.2794 -0.1778)
						)
						(arc
							(start -0.2794 0.1778)
							(mid -0.249642 0.249642)
							(end -0.1778 0.2794)
						)
						(arc
							(start 0.1778 0.2794)
							(mid 0.249642 0.249642)
							(end 0.2794 0.1778)
						)
						(arc
							(start 0.2794 -0.1778)
							(mid 0.249642 -0.249642)
							(end 0.1778 -0.2794)
						)
					)
					(width 0)
					(fill yes)
				)
			)
		)
	)
	(footprint ""
		(layer "F.Cu")
		(at 15.113 -56.134 -90)
		(property "Reference" "R361"
			(at 0 0 270)
			(layer "F.SilkS")
			(hide yes)
			(effects
				(font
					(size 1.27 1.27)
				)
			)
		)
		(property "Value" "100R2J-2-GP"
			(at 0.064008 -3.993896 270)
			(unlocked yes)
			(layer "F.Fab")
			(hide yes)
			(effects
				(font
					(size 1.016 1.016)
					(thickness 0.1524)
				)
			)
		)
		(property "Device Type" "R402H14"
			(at 0.064008 -5.517896 270)
			(unlocked yes)
			(layer "F.Fab")
			(hide yes)
			(effects
				(font
					(size 1.016 1.016)
					(thickness 0.1524)
				)
			)
		)
		(duplicate_pad_numbers_are_jumpers no)
		(fp_line
			(start -0.508 -0.9398)
			(end -0.508 0.9398)
			(stroke
				(width 0.1524)
				(type default)
			)
			(layer "F.SilkS")
		)
		(fp_line
			(start 0.508 -0.9398)
			(end -0.508 -0.9398)
			(stroke
				(width 0.1524)
				(type default)
			)
			(layer "F.SilkS")
		)
		(fp_rect
			(start -0.508 0.9398)
			(end 0.508 -0.9398)
			(stroke
				(width 0)
				(type default)
			)
			(fill no)
			(layer "F.CrtYd")
		)
		(fp_rect
			(start -0.508 0.9398)
			(end 0.508 -0.9398)
			(stroke
				(width 0)
				(type default)
			)
			(fill no)
			(layer "F.Fab")
		)
		(pad "1" smd custom
			(at 0 -0.4445 270)
			(size 0.1397 0.1397)
			(layers "F.Cu" "F.Mask" "F.Paste")
			(net "LOWER_TRAY_ID")
			(options
				(clearance outline)
				(anchor circle)
			)
			(primitives
				(gr_poly
					(pts
						(arc
							(start -0.1778 -0.2794)
							(mid -0.249642 -0.249642)
							(end -0.2794 -0.1778)
						)
						(arc
							(start -0.2794 0.1778)
							(mid -0.249642 0.249642)
							(end -0.1778 0.2794)
						)
						(arc
							(start 0.1778 0.2794)
							(mid 0.249642 0.249642)
							(end 0.2794 0.1778)
						)
						(arc
							(start 0.2794 -0.1778)
							(mid 0.249642 -0.249642)
							(end 0.1778 -0.2794)
						)
					)
					(width 0)
					(fill yes)
				)
			)
		)
		(pad "2" smd custom
			(at 0 0.4445 270)
			(size 0.1397 0.1397)
			(layers "F.Cu" "F.Mask" "F.Paste")
			(net "GND")
			(options
				(clearance outline)
				(anchor circle)
			)
			(primitives
				(gr_poly
					(pts
						(arc
							(start -0.1778 -0.2794)
							(mid -0.249642 -0.249642)
							(end -0.2794 -0.1778)
						)
						(arc
							(start -0.2794 0.1778)
							(mid -0.249642 0.249642)
							(end -0.1778 0.2794)
						)
						(arc
							(start 0.1778 0.2794)
							(mid 0.249642 0.249642)
							(end 0.2794 0.1778)
						)
						(arc
							(start 0.2794 -0.1778)
							(mid 0.249642 -0.249642)
							(end 0.1778 -0.2794)
						)
					)
					(width 0)
					(fill yes)
				)
			)
		)
	)
	(footprint ""
		(layer "F.Cu")
		(at 29.7942 -238.252 180)
		(property "Reference" "R40"
			(at 0 0 180)
			(layer "F.SilkS")
			(hide yes)
			(effects
				(font
					(size 1.27 1.27)
				)
			)
		)
		(property "Value" "4K7R2J-2-GP"
			(at 0.064008 -3.993896 180)
			(unlocked yes)
			(layer "F.Fab")
			(hide yes)
			(effects
				(font
					(size 1.016 1.016)
					(thickness 0.1524)
				)
			)
		)
		(property "Device Type" "R402H16"
			(at 0.064008 -5.517896 180)
			(unlocked yes)
			(layer "F.Fab")
			(hide yes)
			(effects
				(font
					(size 1.016 1.016)
					(thickness 0.1524)
				)
			)
		)
		(duplicate_pad_numbers_are_jumpers no)
		(fp_line
			(start 0.508 -0.9398)
			(end -0.508 -0.9398)
			(stroke
				(width 0.1524)
				(type default)
			)
			(layer "F.SilkS")
		)
		(fp_line
			(start -0.508 -0.9398)
			(end -0.508 0.9398)
			(stroke
				(width 0.1524)
				(type default)
			)
			(layer "F.SilkS")
		)
		(fp_rect
			(start -0.508 0.9398)
			(end 0.508 -0.9398)
			(stroke
				(width 0)
				(type default)
			)
			(fill no)
			(layer "F.CrtYd")
		)
		(fp_rect
			(start -0.508 0.9398)
			(end 0.508 -0.9398)
			(stroke
				(width 0)
				(type default)
			)
			(fill no)
			(layer "F.Fab")
		)
		(pad "1" smd custom
			(at 0 -0.4445 180)
			(size 0.1397 0.1397)
			(layers "F.Cu" "F.Mask" "F.Paste")
			(net "P3V3")
			(options
				(clearance outline)
				(anchor circle)
			)
			(primitives
				(gr_poly
					(pts
						(arc
							(start -0.1778 -0.2794)
							(mid -0.249642 -0.249642)
							(end -0.2794 -0.1778)
						)
						(arc
							(start -0.2794 0.1778)
							(mid -0.249642 0.249642)
							(end -0.1778 0.2794)
						)
						(arc
							(start 0.1778 0.2794)
							(mid 0.249642 0.249642)
							(end 0.2794 0.1778)
						)
						(arc
							(start 0.2794 -0.1778)
							(mid 0.249642 -0.249642)
							(end 0.1778 -0.2794)
						)
					)
					(width 0)
					(fill yes)
				)
			)
		)
		(pad "2" smd custom
			(at 0 0.4445 180)
			(size 0.1397 0.1397)
			(layers "F.Cu" "F.Mask" "F.Paste")
			(net "FCB_EEPROM_A1")
			(options
				(clearance outline)
				(anchor circle)
			)
			(primitives
				(gr_poly
					(pts
						(arc
							(start -0.1778 -0.2794)
							(mid -0.249642 -0.249642)
							(end -0.2794 -0.1778)
						)
						(arc
							(start -0.2794 0.1778)
							(mid -0.249642 0.249642)
							(end -0.1778 0.2794)
						)
						(arc
							(start 0.1778 0.2794)
							(mid 0.249642 0.249642)
							(end 0.2794 0.1778)
						)
						(arc
							(start 0.2794 -0.1778)
							(mid 0.249642 -0.249642)
							(end 0.1778 -0.2794)
						)
					)
					(width 0)
					(fill yes)
				)
			)
		)
	)
)
